#ISCELL
  mstr_misc dns *
  *
#ISCELL
  pure_quanta quanta_title_block_c *
  *
#ISCELL
  pure_quanta_power universal_gnd *
  page160_i1
#ISCELL
  standard offpage *
  page160_i10
#ISCELL
  standard offpage *
  page160_i11
#ISCELL
  standard offpage *
  page160_i12
#ISCELL
  standard offpage *
  page160_i13
#ISCELL
  pure_quanta_power universal_power *
  page160_i14
#ISCELL
  standard offpage *
  page160_i15
#ISCELL
  pure_quanta_power universal_gnd *
  page160_i16
#ISCELL
  pure_quanta_power universal_power *
  page160_i17
#CELL
  pure_quanta q_cap *
  page160_i18
#ISCELL
  pure_quanta_power universal_gnd *
  page160_i19
#CELL
  pure_quanta q_res *
  page160_i2
#CELL
  pure_quanta q_cap *
  page160_i20
#ISCELL
  pure_quanta_power universal_power *
  page160_i21
#ISCELL
  pure_quanta_power universal_power *
  page160_i22
#ISCELL
  pure_quanta_power universal_power *
  page160_i23
#CELL
  pure_quanta q_inductor *
  page160_i24
#ISCELL
  pure_quanta_power universal_power *
  page160_i25
#CELL
  pure_quanta q_inductor *
  page160_i26
#CELL
  pure_quanta q_res *
  page160_i27
#ISCELL
  pure_quanta_power universal_power *
  page160_i28
#CELL
  pure_quanta q_res *
  page160_i29
#CELL
  pure_quanta q_res *
  page160_i3
#ISCELL
  pure_quanta_power universal_gnd *
  page160_i30
#CELL
  pure_quanta q_res *
  page160_i31
#ISCELL
  standard offpage *
  page160_i32
#ISCELL
  pure_quanta_power universal_power *
  page160_i33
#ISCELL
  pure_quanta_power universal_gnd *
  page160_i34
#ISCELL
  standard offpage *
  page160_i4
#CELL
  pure_quanta q_cap *
  page160_i40
#CELL
  pure_quanta q_cap *
  page160_i41
#ISCELL
  pure_quanta_power universal_power *
  page160_i42
#ISCELL
  standard offpage *
  page160_i43
#CELL
  pure_quanta q_cap *
  page160_i44
#CELL
  pure_quanta q_cap *
  page160_i45
#ISCELL
  pure_quanta_power universal_gnd *
  page160_i46
#CELL
  pure_quanta q_cap *
  page160_i47
#ISCELL
  pure_quanta_power universal_power *
  page160_i48
#ISCELL
  standard offpage *
  page160_i49
#ISCELL
  standard offpage *
  page160_i50
#ISCELL
  standard offpage *
  page160_i51
#CELL
  pure_quanta q_res *
  page160_i52
#CELL
  pure_quanta q_res *
  page160_i53
#CELL
  pure_quanta q_res *
  page160_i55
#ISCELL
  standard offpage *
  page160_i58
#ISCELL
  standard offpage *
  page160_i59
#CELL
  pure_quanta q_res *
  page160_i6
#ISCELL
  standard offpage *
  page160_i60
#CELL
  pure_quanta 9zxl0451ekilft *
  page160_i63
#ISCELL
  standard offpage *
  page160_i64
#ISCELL
  standard offpage *
  page160_i65
#CELL
  pure_quanta q_res *
  page160_i68
#CELL
  pure_quanta q_cap *
  page160_i69
#CELL
  pure_quanta q_cap *
  page160_i70
#CELL
  pure_quanta q_cap *
  page160_i71
#ISCELL
  pure_quanta_power universal_gnd *
  page160_i72
#CELL
  pure_quanta q_res *
  page160_i73
#ISCELL
  pure_quanta_power universal_power *
  page160_i74
